(kicad_pcb
	(version 20241229)
	(generator "pcbnew")
	(generator_version "9.0")
	(general
		(thickness 1.294)
		(legacy_teardrops no)
	)
	(paper "A3")
	(title_block
		(title "Kintex 410T devboard")
		(date "2024-04-03")
		(rev "1.1.2")
		(comment 9 "footprints 490-495 of 975")
	)
	(layers
		(0 "F.Cu" mixed)
		(4 "In1.Cu" power)
		(6 "In2.Cu" power)
		(8 "In3.Cu" mixed)
		(10 "In4.Cu" power)
		(12 "In5.Cu" mixed)
		(14 "In6.Cu" power)
		(16 "In7.Cu" mixed)
		(18 "In8.Cu" power)
		(2 "B.Cu" mixed)
		(9 "F.Adhes" user "F.Adhesive")
		(11 "B.Adhes" user "B.Adhesive")
		(13 "F.Paste" user)
		(15 "B.Paste" user)
		(5 "F.SilkS" user "F.Silkscreen")
		(7 "B.SilkS" user "B.Silkscreen")
		(1 "F.Mask" user)
		(3 "B.Mask" user)
		(17 "Dwgs.User" user "User.Drawings")
		(19 "Cmts.User" user "User.Comments")
		(21 "Eco1.User" user "User.Eco1")
		(23 "Eco2.User" user "User.Eco2")
		(25 "Edge.Cuts" user)
		(27 "Margin" user)
		(31 "F.CrtYd" user "F.Courtyard")
		(29 "B.CrtYd" user "B.Courtyard")
		(35 "F.Fab" user)
		(33 "B.Fab" user)
	)
	(footprint "antmicro-footprints:C_0603_1608Metric"
		(layer "B.Cu")
		(at 191.2 114 180)
		(descr "Capacitor SMD 0603")
		(tags "capacitor 0603")
		(property "Reference" "C112"
			(at -1.45 0.575 0)
			(layer "B.SilkS")
			(effects
				(font
					(size 0.7 0.7)
					(thickness 0.15)
				)
				(justify left bottom mirror)
			)
		)
		(property "Value" "C_47u_0603"
			(at 0 -1.6 0)
			(layer "B.Fab")
			(effects
				(font
					(size 0.7 0.7)
					(thickness 0.15)
				)
				(justify left bottom mirror)
			)
		)
		(property "Description" "SMD Multilayer Ceramic Capacitor, 47 µF, 6.3 V, 0603 [1608 Metric], ± 20%, X5R, GRM Series"
			(at 0 0 180)
			(layer "F.Fab")
			(hide yes)
			(effects
				(font
					(size 1.27 1.27)
					(thickness 0.15)
				)
			)
		)
		(property "Author" "Antmicro"
			(at 382.4 228 0)
			(layer "B.Fab")
			(hide yes)
			(effects
				(font
					(size 1 1)
					(thickness 0.15)
				)
				(justify mirror)
			)
		)
		(property "Dielectric" ""
			(at 382.4 228 0)
			(layer "B.Fab")
			(hide yes)
			(effects
				(font
					(size 1 1)
					(thickness 0.15)
				)
				(justify mirror)
			)
		)
		(property "License" "Apache-2.0"
			(at 382.4 228 0)
			(layer "B.Fab")
			(hide yes)
			(effects
				(font
					(size 1 1)
					(thickness 0.15)
				)
				(justify mirror)
			)
		)
		(property "MPN" "GRM188R60J476ME15D"
			(at 382.4 228 0)
			(layer "B.Fab")
			(hide yes)
			(effects
				(font
					(size 1 1)
					(thickness 0.15)
				)
				(justify mirror)
			)
		)
		(property "Manufacturer" "Murata"
			(at 382.4 228 0)
			(layer "B.Fab")
			(hide yes)
			(effects
				(font
					(size 1 1)
					(thickness 0.15)
				)
				(justify mirror)
			)
		)
		(property "Val" "47u"
			(at 382.4 228 0)
			(layer "B.Fab")
			(hide yes)
			(effects
				(font
					(size 1 1)
					(thickness 0.15)
				)
				(justify mirror)
			)
		)
		(property "Voltage" ""
			(at 382.4 228 0)
			(layer "B.Fab")
			(hide yes)
			(effects
				(font
					(size 1 1)
					(thickness 0.15)
				)
				(justify mirror)
			)
		)
		(sheetname "FPGA supply")
		(sheetfile "fpga-supply.kicad_sch")
		(attr smd)
		(fp_line
			(start -0.15 0.4)
			(end 0.15 0.4)
			(stroke
				(width 0.15)
				(type solid)
			)
			(layer "B.SilkS")
		)
		(fp_line
			(start -0.15 -0.4)
			(end 0.15 -0.4)
			(stroke
				(width 0.15)
				(type solid)
			)
			(layer "B.SilkS")
		)
		(fp_rect
			(start -1.25 0.65)
			(end 1.25 -0.65)
			(stroke
				(width 0.05)
				(type solid)
			)
			(fill no)
			(layer "B.CrtYd")
		)
		(fp_rect
			(start -0.8 0.4)
			(end 0.8 -0.4)
			(stroke
				(width 0.15)
				(type solid)
			)
			(fill no)
			(layer "B.Fab")
		)
		(pad "1" smd roundrect
			(at -0.7 0 180)
			(size 0.8 1)
			(layers "B.Cu" "B.Mask" "B.Paste")
			(roundrect_rratio 0.2)
			(net 6 "+1V0_MGTAVCC")
			(pintype "passive")
		)
		(pad "2" smd roundrect
			(at 0.7 0 180)
			(size 0.8 1)
			(layers "B.Cu" "B.Mask" "B.Paste")
			(roundrect_rratio 0.2)
			(net 1 "GND")
			(pintype "passive")
		)
	)
	(footprint "antmicro-footprints:R_0402_1005Metric"
		(layer "B.Cu")
		(at 251.001 129.7 180)
		(descr "Resistor SMD 0402")
		(tags "resistor SMD 0402")
		(property "Reference" "R98"
			(at -1.274 -1.275 0)
			(layer "B.SilkS")
			(effects
				(font
					(size 0.7 0.7)
					(thickness 0.15)
				)
				(justify left bottom mirror)
			)
		)
		(property "Value" "R_100R_0402"
			(at 0 -1.4 0)
			(layer "B.Fab")
			(effects
				(font
					(size 0.7 0.7)
					(thickness 0.15)
				)
				(justify left bottom mirror)
			)
		)
		(property "Description" "SMD Chip Resistor, 100 ohm, ± 1%, 62.5 mW, 0402 [1005 Metric], Thick Film, General Purpose"
			(at 0 0 180)
			(layer "F.Fab")
			(hide yes)
			(effects
				(font
					(size 1.27 1.27)
					(thickness 0.15)
				)
			)
		)
		(property "Author" "Antmicro"
			(at 502.002 259.4 0)
			(layer "B.Fab")
			(hide yes)
			(effects
				(font
					(size 1 1)
					(thickness 0.15)
				)
				(justify mirror)
			)
		)
		(property "License" "Apache-2.0"
			(at 502.002 259.4 0)
			(layer "B.Fab")
			(hide yes)
			(effects
				(font
					(size 1 1)
					(thickness 0.15)
				)
				(justify mirror)
			)
		)
		(property "MPN" "CR0402-FX-1000GLF"
			(at 502.002 259.4 0)
			(layer "B.Fab")
			(hide yes)
			(effects
				(font
					(size 1 1)
					(thickness 0.15)
				)
				(justify mirror)
			)
		)
		(property "Manufacturer" "Bourns"
			(at 502.002 259.4 0)
			(layer "B.Fab")
			(hide yes)
			(effects
				(font
					(size 1 1)
					(thickness 0.15)
				)
				(justify mirror)
			)
		)
		(property "Tolerance" "1%"
			(at 502.002 259.4 0)
			(layer "B.Fab")
			(hide yes)
			(effects
				(font
					(size 1 1)
					(thickness 0.15)
				)
				(justify mirror)
			)
		)
		(property "Val" "100R"
			(at 502.002 259.4 0)
			(layer "B.Fab")
			(hide yes)
			(effects
				(font
					(size 1 1)
					(thickness 0.15)
				)
				(justify mirror)
			)
		)
		(sheetname "SPI Flash + SD Card")
		(sheetfile "spi-flash.kicad_sch")
		(attr smd)
		(fp_rect
			(start -0.925 0.47)
			(end 0.925 -0.47)
			(stroke
				(width 0.05)
				(type default)
			)
			(fill no)
			(layer "B.CrtYd")
		)
		(fp_rect
			(start -0.5 0.25)
			(end 0.5 -0.25)
			(stroke
				(width 0.15)
				(type solid)
			)
			(fill no)
			(layer "B.Fab")
		)
		(pad "1" smd roundrect
			(at -0.48 0 180)
			(size 0.59 0.64)
			(layers "B.Cu" "B.Mask" "B.Paste")
			(roundrect_rratio 0.25)
			(net 74 "/SPI Flash + SD Card/SD_CARD_~{CD}")
			(pintype "passive")
		)
		(pad "2" smd roundrect
			(at 0.48 0 180)
			(size 0.59 0.64)
			(layers "B.Cu" "B.Mask" "B.Paste")
			(roundrect_rratio 0.25)
			(net 416 "/FPGA Bank 33 & 34/SD_CARD.~{CD}")
			(pintype "passive")
		)
	)
	(footprint "antmicro-footprints:C_0201"
		(layer "B.Cu")
		(at 188.000001 130.500001 180)
		(descr "Capacitor SMD 0201")
		(tags "capacitor SMD 0201")
		(property "Reference" "C151"
			(at 0.550001 -0.349999 0)
			(layer "B.SilkS")
			(effects
				(font
					(size 0.7 0.7)
					(thickness 0.15)
				)
				(justify left bottom mirror)
			)
		)
		(property "Value" "C_100n_0201"
			(at 0 -1.4 0)
			(layer "B.Fab")
			(effects
				(font
					(size 0.7 0.7)
					(thickness 0.15)
				)
				(justify left bottom mirror)
			)
		)
		(property "Description" "SMD Multilayer Ceramic Capacitor, 0.1 µF, 6.3 V, 0201 [0603 Metric], ± 10%, X6S, CC Series"
			(at 0 0 180)
			(layer "F.Fab")
			(hide yes)
			(effects
				(font
					(size 1.27 1.27)
					(thickness 0.15)
				)
			)
		)
		(property "Author" "Antmicro"
			(at 376.000002 261.000002 0)
			(layer "B.Fab")
			(hide yes)
			(effects
				(font
					(size 1 1)
					(thickness 0.15)
				)
				(justify mirror)
			)
		)
		(property "Dielectric" ""
			(at 376.000002 261.000002 0)
			(layer "B.Fab")
			(hide yes)
			(effects
				(font
					(size 1 1)
					(thickness 0.15)
				)
				(justify mirror)
			)
		)
		(property "License" "Apache-2.0"
			(at 376.000002 261.000002 0)
			(layer "B.Fab")
			(hide yes)
			(effects
				(font
					(size 1 1)
					(thickness 0.15)
				)
				(justify mirror)
			)
		)
		(property "MPN" "CC0201KRX6S5BB104"
			(at 376.000002 261.000002 0)
			(layer "B.Fab")
			(hide yes)
			(effects
				(font
					(size 1 1)
					(thickness 0.15)
				)
				(justify mirror)
			)
		)
		(property "Manufacturer" "YAGEO"
			(at 376.000002 261.000002 0)
			(layer "B.Fab")
			(hide yes)
			(effects
				(font
					(size 1 1)
					(thickness 0.15)
				)
				(justify mirror)
			)
		)
		(property "Val" "100n"
			(at 376.000002 261.000002 0)
			(layer "B.Fab")
			(hide yes)
			(effects
				(font
					(size 1 1)
					(thickness 0.15)
				)
				(justify mirror)
			)
		)
		(property "Voltage" ""
			(at 376.000002 261.000002 0)
			(layer "B.Fab")
			(hide yes)
			(effects
				(font
					(size 1 1)
					(thickness 0.15)
				)
				(justify mirror)
			)
		)
		(sheetname "FPGA supply")
		(sheetfile "fpga-supply.kicad_sch")
		(attr smd)
		(fp_rect
			(start -0.7 0.35)
			(end 0.7 -0.35)
			(stroke
				(width 0.05)
				(type default)
			)
			(fill no)
			(layer "B.CrtYd")
		)
		(fp_rect
			(start 0.3 -0.15)
			(end -0.301 0.149)
			(stroke
				(width 0.15)
				(type solid)
			)
			(fill no)
			(layer "B.Fab")
		)
		(pad "" smd roundrect
			(at -0.349 0.002 180)
			(size 0.318 0.36)
			(layers "B.Paste")
			(roundrect_rratio 0.25)
		)
		(pad "" smd roundrect
			(at 0.341 0.002 180)
			(size 0.318 0.36)
			(layers "B.Paste")
			(roundrect_rratio 0.25)
		)
		(pad "1" smd roundrect
			(at -0.321 0.002 180)
			(size 0.46 0.4)
			(layers "B.Cu" "B.Mask")
			(roundrect_rratio 0.25)
			(net 1 "GND")
			(pintype "passive")
		)
		(pad "2" smd roundrect
			(at 0.32 0.002 180)
			(size 0.46 0.4)
			(layers "B.Cu" "B.Mask")
			(roundrect_rratio 0.25)
			(net 8 "+1V2_MGTAVTT")
			(pintype "passive")
		)
	)
	(footprint "antmicro-footprints:R_0402_1005Metric"
		(layer "B.Cu")
		(at 266.001 126.7)
		(descr "Resistor SMD 0402")
		(tags "resistor SMD 0402")
		(property "Reference" "R172"
			(at -0.901 0.675 180)
			(layer "B.SilkS")
			(effects
				(font
					(size 0.7 0.7)
					(thickness 0.15)
				)
				(justify left bottom mirror)
			)
		)
		(property "Value" "R_1k5_0402"
			(at 0 -1.4 180)
			(layer "B.Fab")
			(effects
				(font
					(size 0.7 0.7)
					(thickness 0.15)
				)
				(justify left bottom mirror)
			)
		)
		(property "Description" "SMD Chip Resistor, 1.5 kohm, ± 1%, 62.5 mW, 0402 [1005 Metric], Thick Film, General Purpose"
			(at 0 0 0)
			(layer "F.Fab")
			(hide yes)
			(effects
				(font
					(size 1.27 1.27)
					(thickness 0.15)
				)
			)
		)
		(property "Author" "Antmicro"
			(at 0 0 0)
			(layer "B.Fab")
			(hide yes)
			(effects
				(font
					(size 1 1)
					(thickness 0.15)
				)
				(justify mirror)
			)
		)
		(property "DNP" "DNP"
			(at 0 0 0)
			(layer "B.Fab")
			(hide yes)
			(effects
				(font
					(size 1 1)
					(thickness 0.15)
				)
				(justify mirror)
			)
		)
		(property "License" "Apache-2.0"
			(at 0 0 0)
			(layer "B.Fab")
			(hide yes)
			(effects
				(font
					(size 1 1)
					(thickness 0.15)
				)
				(justify mirror)
			)
		)
		(property "MPN" "CR0402-FX-1501GLF"
			(at 0 0 0)
			(layer "B.Fab")
			(hide yes)
			(effects
				(font
					(size 1 1)
					(thickness 0.15)
				)
				(justify mirror)
			)
		)
		(property "Manufacturer" "Bourns"
			(at 0 0 0)
			(layer "B.Fab")
			(hide yes)
			(effects
				(font
					(size 1 1)
					(thickness 0.15)
				)
				(justify mirror)
			)
		)
		(property "Tolerance" "1%"
			(at 0 0 0)
			(layer "B.Fab")
			(hide yes)
			(effects
				(font
					(size 1 1)
					(thickness 0.15)
				)
				(justify mirror)
			)
		)
		(property "Val" "1k5"
			(at 0 0 0)
			(layer "B.Fab")
			(hide yes)
			(effects
				(font
					(size 1 1)
					(thickness 0.15)
				)
				(justify mirror)
			)
		)
		(property "dnp" ""
			(at 0 0 0)
			(layer "B.Fab")
			(hide yes)
			(effects
				(font
					(size 1 1)
					(thickness 0.15)
				)
				(justify mirror)
			)
		)
		(property "exclude_from_bom" ""
			(at 0 0 0)
			(layer "B.Fab")
			(hide yes)
			(effects
				(font
					(size 1 1)
					(thickness 0.15)
				)
				(justify mirror)
			)
		)
		(sheetname "USB PHY")
		(sheetfile "usb-phy.kicad_sch")
		(attr smd exclude_from_bom)
		(fp_rect
			(start -0.925 0.47)
			(end 0.925 -0.47)
			(stroke
				(width 0.05)
				(type default)
			)
			(fill no)
			(layer "B.CrtYd")
		)
		(fp_rect
			(start -0.5 0.25)
			(end 0.5 -0.25)
			(stroke
				(width 0.15)
				(type solid)
			)
			(fill no)
			(layer "B.Fab")
		)
		(pad "1" smd roundrect
			(at -0.48 0)
			(size 0.59 0.64)
			(layers "B.Cu" "B.Mask" "B.Paste")
			(roundrect_rratio 0.25)
			(net 843 "/USB PHY/USB_USR_CONN_D-")
			(pintype "passive")
		)
		(pad "2" smd roundrect
			(at 0.48 0)
			(size 0.59 0.64)
			(layers "B.Cu" "B.Mask" "B.Paste")
			(roundrect_rratio 0.25)
			(net 926 "/USB PHY/USB_USR_VPU")
			(pintype "passive")
		)
	)
	(footprint "antmicro-footprints:R_0402_1005Metric"
		(layer "B.Cu")
		(at 168.55 185.95 -90)
		(descr "Resistor SMD 0402")
		(tags "resistor SMD 0402")
		(property "Reference" "R322"
			(at -3.625 -0.525 90)
			(layer "B.SilkS")
			(effects
				(font
					(size 0.7 0.7)
					(thickness 0.15)
				)
				(justify left bottom mirror)
			)
		)
		(property "Value" "R_47k_0402"
			(at 0 -1.4 90)
			(layer "B.Fab")
			(effects
				(font
					(size 0.7 0.7)
					(thickness 0.15)
				)
				(justify left bottom mirror)
			)
		)
		(property "Description" "SMD Chip Resistor, 47 kohm, ± 1%, 62.5 mW, 0402 [1005 Metric], Thick Film, General Purpose"
			(at 0 0 270)
			(layer "F.Fab")
			(hide yes)
			(effects
				(font
					(size 1.27 1.27)
					(thickness 0.15)
				)
			)
		)
		(property "Author" "Antmicro"
			(at -17.4 354.5 0)
			(layer "B.Fab")
			(hide yes)
			(effects
				(font
					(size 1 1)
					(thickness 0.15)
				)
				(justify mirror)
			)
		)
		(property "License" "Apache-2.0"
			(at -17.4 354.5 0)
			(layer "B.Fab")
			(hide yes)
			(effects
				(font
					(size 1 1)
					(thickness 0.15)
				)
				(justify mirror)
			)
		)
		(property "MPN" "CR0402-FX-4702GLF"
			(at -17.4 354.5 0)
			(layer "B.Fab")
			(hide yes)
			(effects
				(font
					(size 1 1)
					(thickness 0.15)
				)
				(justify mirror)
			)
		)
		(property "Manufacturer" "Bourns"
			(at -17.4 354.5 0)
			(layer "B.Fab")
			(hide yes)
			(effects
				(font
					(size 1 1)
					(thickness 0.15)
				)
				(justify mirror)
			)
		)
		(property "Tolerance" "1%"
			(at -17.4 354.5 0)
			(layer "B.Fab")
			(hide yes)
			(effects
				(font
					(size 1 1)
					(thickness 0.15)
				)
				(justify mirror)
			)
		)
		(property "Val" "47k"
			(at -17.4 354.5 0)
			(layer "B.Fab")
			(hide yes)
			(effects
				(font
					(size 1 1)
					(thickness 0.15)
				)
				(justify mirror)
			)
		)
		(sheetname "DC-DC Converters")
		(sheetfile "dc-dc.kicad_sch")
		(attr smd)
		(fp_rect
			(start -0.925 0.47)
			(end 0.925 -0.47)
			(stroke
				(width 0.05)
				(type default)
			)
			(fill no)
			(layer "B.CrtYd")
		)
		(fp_rect
			(start -0.5 0.25)
			(end 0.5 -0.25)
			(stroke
				(width 0.15)
				(type solid)
			)
			(fill no)
			(layer "B.Fab")
		)
		(pad "1" smd roundrect
			(at -0.48 0 270)
			(size 0.59 0.64)
			(layers "B.Cu" "B.Mask" "B.Paste")
			(roundrect_rratio 0.25)
			(net 968 "/DC-DC Converters/EN3")
			(pintype "passive")
		)
		(pad "2" smd roundrect
			(at 0.48 0 270)
			(size 0.59 0.64)
			(layers "B.Cu" "B.Mask" "B.Paste")
			(roundrect_rratio 0.25)
			(net 37 "+3V3_AON")
			(pintype "passive")
		)
	)
	(footprint "antmicro-footprints:R_0402_1005Metric"
		(layer "B.Cu")
		(at 195.691252 94.85 180)
		(descr "Resistor SMD 0402")
		(tags "resistor SMD 0402")
		(property "Reference" "R202"
			(at 0.716252 -0.425 0)
			(layer "B.SilkS")
			(effects
				(font
					(size 0.7 0.7)
					(thickness 0.15)
				)
				(justify left bottom mirror)
			)
		)
		(property "Value" "R_10k_0402"
			(at 0 -1.4 0)
			(layer "B.Fab")
			(effects
				(font
					(size 0.7 0.7)
					(thickness 0.15)
				)
				(justify left bottom mirror)
			)
		)
		(property "Description" "SMD Chip Resistor, 10 kohm, ± 1%, 62.5 mW, 0402 [1005 Metric], Thick Film, General Purpose"
			(at 0 0 180)
			(layer "F.Fab")
			(hide yes)
			(effects
				(font
					(size 1.27 1.27)
					(thickness 0.15)
				)
			)
		)
		(property "Author" "Antmicro"
			(at 391.382504 189.7 0)
			(layer "B.Fab")
			(hide yes)
			(effects
				(font
					(size 1 1)
					(thickness 0.15)
				)
				(justify mirror)
			)
		)
		(property "DNP" "DNP"
			(at 391.382504 189.7 0)
			(layer "B.Fab")
			(hide yes)
			(effects
				(font
					(size 1 1)
					(thickness 0.15)
				)
				(justify mirror)
			)
		)
		(property "License" "Apache-2.0"
			(at 391.382504 189.7 0)
			(layer "B.Fab")
			(hide yes)
			(effects
				(font
					(size 1 1)
					(thickness 0.15)
				)
				(justify mirror)
			)
		)
		(property "MPN" "CR0402-FX-1002GLF"
			(at 391.382504 189.7 0)
			(layer "B.Fab")
			(hide yes)
			(effects
				(font
					(size 1 1)
					(thickness 0.15)
				)
				(justify mirror)
			)
		)
		(property "Manufacturer" "Bourns"
			(at 391.382504 189.7 0)
			(layer "B.Fab")
			(hide yes)
			(effects
				(font
					(size 1 1)
					(thickness 0.15)
				)
				(justify mirror)
			)
		)
		(property "Tolerance" "1%"
			(at 391.382504 189.7 0)
			(layer "B.Fab")
			(hide yes)
			(effects
				(font
					(size 1 1)
					(thickness 0.15)
				)
				(justify mirror)
			)
		)
		(property "Val" "10k"
			(at 391.382504 189.7 0)
			(layer "B.Fab")
			(hide yes)
			(effects
				(font
					(size 1 1)
					(thickness 0.15)
				)
				(justify mirror)
			)
		)
		(property "dnp" ""
			(at 391.382504 189.7 0)
			(layer "B.Fab")
			(hide yes)
			(effects
				(font
					(size 1 1)
					(thickness 0.15)
				)
				(justify mirror)
			)
		)
		(property "exclude_from_bom" ""
			(at 391.382504 189.7 0)
			(layer "B.Fab")
			(hide yes)
			(effects
				(font
					(size 1 1)
					(thickness 0.15)
				)
				(justify mirror)
			)
		)
		(sheetname "HDMI + Ethernet")
		(sheetfile "hdmi-ethernet.kicad_sch")
		(attr smd exclude_from_bom)
		(fp_rect
			(start -0.925 0.47)
			(end 0.925 -0.47)
			(stroke
				(width 0.05)
				(type default)
			)
			(fill no)
			(layer "B.CrtYd")
		)
		(fp_rect
			(start -0.5 0.25)
			(end 0.5 -0.25)
			(stroke
				(width 0.15)
				(type solid)
			)
			(fill no)
			(layer "B.Fab")
		)
		(pad "1" smd roundrect
			(at -0.48 0 180)
			(size 0.59 0.64)
			(layers "B.Cu" "B.Mask" "B.Paste")
			(roundrect_rratio 0.25)
			(net 506 "/FPGA Bank 16 & 17/GBE_RGMII.RXD0")
			(pintype "passive")
		)
		(pad "2" smd roundrect
			(at 0.48 0 180)
			(size 0.59 0.64)
			(layers "B.Cu" "B.Mask" "B.Paste")
			(roundrect_rratio 0.25)
			(net 24 "+3V3")
			(pintype "passive")
		)
	)
)
